# T6G (Grand Teton) — schematic parts with pin connectivity, parts 8233–8233 of 8303; source: Cadence DE-HDL packaged netlist (pstxprt.dat, pstxnet.dat, pstchip.dat)

U6016  PT5161LRS  IC  pkg BGA354_8-9X22-8  page 340
  A1  NCF_GND1  POWER  = NCF_A1_CPU1_P2_GND
  A35  NCF_GND2  POWER  = NCF_CPU1_P2_GND
  AA10  B_PETN1  OUT  = P5E_CPU1_P2_TX_BUF_DN<14>
  AA29  A_PETN1  OUT  = P5E_CPU1_P2_RX_DN<14>
  AB1  A_PERP1  IN  = P5E_CPU1_P2_RX_BUF_DP<14>
  AB35  B_PERN1  IN  = P5E_CPU1_P2_TX_C_DP<14>
  AC4  GND4  POWER  = GND
  AC13  GND1  POWER  = GND
  AC17  PWR_2A_1  POWER  = P0V9_CPU1_RT2_2A
  AC20  PWR_2A_2  POWER  = P0V9_CPU1_RT2_2A
  AC22  GND2  POWER  = GND
  AC32  GND3  POWER  = GND
  AD2  GND5  POWER  = GND
  AD34  GND6  POWER  = GND
  AE1  GND7  POWER  = GND
  AE35  GND8  POWER  = GND
  AF7  B_PETP2  OUT  = P5E_CPU1_P2_TX_BUF_DP<13>
  AF26  A_PETP2  OUT  = P5E_CPU1_P2_RX_DP<13>
  AG2  A_PERN2  IN  = P5E_CPU1_P2_RX_BUF_DN<13>
  AG34  B_PERP2  IN  = P5E_CPU1_P2_TX_C_DN<13>
  AH10  B_PETN2  OUT  = P5E_CPU1_P2_TX_BUF_DN<13>
  AH29  A_PETN2  OUT  = P5E_CPU1_P2_RX_DN<13>
  AJ1  A_PERP2  IN  = P5E_CPU1_P2_RX_BUF_DP<13>
  AJ35  B_PERN2  IN  = P5E_CPU1_P2_TX_C_DP<13>
  AK4  GND12  POWER  = GND
  AK13  GND9  POWER  = GND
  AK17  PWR_2A_3  POWER  = P0V9_CPU1_RT2_2A
  AK20  PWR_2A_4  POWER  = P0V9_CPU1_RT2_2A
  AK22  GND10  POWER  = GND
  AK32  GND11  POWER  = GND
  AL2  GND13  POWER  = GND
  AL34  GND14  POWER  = GND
  AM1  GND15  POWER  = GND
  AM35  GND16  POWER  = GND
  AN7  B_PETP3  OUT  = P5E_CPU1_P2_TX_BUF_DP<12>
  AN26  A_PETP3  OUT  = P5E_CPU1_P2_RX_DP<12>
  AP2  A_PERN3  IN  = P5E_CPU1_P2_RX_BUF_DN<12>
  AP34  B_PERP3  IN  = P5E_CPU1_P2_TX_C_DN<12>
  AR10  B_PETN3  OUT  = P5E_CPU1_P2_TX_BUF_DN<12>
  AR29  A_PETN3  OUT  = P5E_CPU1_P2_RX_DN<12>
  AT1  A_PERP3  IN  = P5E_CPU1_P2_RX_BUF_DP<12>
  AT35  B_PERN3  IN  = P5E_CPU1_P2_TX_C_DP<12>
  AU4  GND20  POWER  = GND
  AU13  GND17  POWER  = GND
  AU17  PWR_2A_5  POWER  = P0V9_CPU1_RT2_2A
  AU20  PWR_2A_6  POWER  = P0V9_CPU1_RT2_2A
  AU22  GND18  POWER  = GND
  AU32  GND19  POWER  = GND
  AV2  GND21  POWER  = GND
  AV34  GND22  POWER  = GND
  AW1  GND23  POWER  = GND
  AW35  GND24  POWER  = GND
  AY7  B_PETP4  OUT  = P5E_CPU1_P2_TX_BUF_DP<11>
  AY26  A_PETP4  OUT  = P5E_CPU1_P2_RX_DP<11>
  B3  JTAG_TCK  IN  = JTAG_TCK_RT_CPU1_P2
  B6  JTAG_TDI  IN  = JTAG_TDI_RT_CPU1_P2
  B9  JTAG_TDO  OUT  = JTAG_TDO_RT_CPU1_P2
  B12  JTAG_TMS  IN  = JTAG_TMS_RT_CPU1_P2
  B16  REFCLK_OUTP  OUT  = NC
  B19  GND25  POWER  = GND
  B23  SMB_ADDR2  IN  = RT_CPU1_P2_ADDR2
  B25  SMB_ADDR3  IN  = RT_CPU1_P2_ADDR3
  B28  SMBDAT  BI  = SMB_RT_CPU1_P2_R2_SDA
  B31  SMBCLK  BI  = SMB_RT_CPU1_P2_R2_SCL
  BA2  A_PERN4  IN  = P5E_CPU1_P2_RX_BUF_DN<11>
  BA34  B_PERP4  IN  = P5E_CPU1_P2_TX_C_DN<11>
  BB10  B_PETN4  OUT  = P5E_CPU1_P2_TX_BUF_DN<11>
  BB29  A_PETN4  OUT  = P5E_CPU1_P2_RX_DN<11>
  BC1  A_PERP4  IN  = P5E_CPU1_P2_RX_BUF_DP<11>
  BC35  B_PERN4  IN  = P5E_CPU1_P2_TX_C_DP<11>
  BD4  GND29  POWER  = GND
  BD13  GND26  POWER  = GND
  BD17  PWR_2A_7  POWER  = P0V9_CPU1_RT2_2A_2D
  BD20  PWR_2A_8  POWER  = P0V9_CPU1_RT2_2A_2D
  BD22  GND27  POWER  = GND
  BD32  GND28  POWER  = GND
  BE2  GND30  POWER  = GND
  BE34  GND31  POWER  = GND
  BF1  GND32  POWER  = GND
  BF35  GND33  POWER  = GND
  BG7  B_PETP5  OUT  = P5E_CPU1_P2_TX_BUF_DP<10>
  BG26  A_PETP5  OUT  = P5E_CPU1_P2_RX_DP<10>
  BH2  A_PERN5  IN  = P5E_CPU1_P2_RX_BUF_DN<10>
  BH34  B_PERP5  IN  = P5E_CPU1_P2_TX_C_DN<10>
  BJ10  B_PETN5  OUT  = P5E_CPU1_P2_TX_BUF_DN<10>
  BJ29  A_PETN5  OUT  = P5E_CPU1_P2_RX_DN<10>
  BK1  A_PERP5  IN  = P5E_CPU1_P2_RX_BUF_DP<10>
  BK35  B_PERN5  IN  = P5E_CPU1_P2_TX_C_DP<10>
  BL4  GND37  POWER  = GND
  BL13  GND34  POWER  = GND
  BL17  PWR_2D_1  POWER  = P0V9_CPU1_RT_2D
  BL20  PWR_2D_2  POWER  = P0V9_CPU1_RT_2D
  BL22  GND35  POWER  = GND
  BL32  GND36  POWER  = GND
  BM2  GND38  POWER  = GND
  BM34  GND39  POWER  = GND
  BN1  GND40  POWER  = GND
  BN35  GND41  POWER  = GND
  BP7  B_PETP6  OUT  = P5E_CPU1_P2_TX_BUF_DP<9>
  BP26  A_PETP6  OUT  = P5E_CPU1_P2_RX_DP<9>
  BR2  A_PERN6  IN  = P5E_CPU1_P2_RX_BUF_DN<9>
  BR34  B_PERP6  IN  = P5E_CPU1_P2_TX_C_DN<9>
  BT10  B_PETN6  OUT  = P5E_CPU1_P2_TX_BUF_DN<9>
  BT29  A_PETN6  OUT  = P5E_CPU1_P2_RX_DN<9>
  BU1  A_PERP6  IN  = P5E_CPU1_P2_RX_BUF_DP<9>
  BU35  B_PERN6  IN  = P5E_CPU1_P2_TX_C_DP<9>
  BV4  GND45  POWER  = GND
  BV13  GND42  POWER  = GND
  BV17  PWR_1D  POWER  = P1V8_CPU1_RT2_1A_1D
  BV20  PWR_1A_1  POWER  = P1V8_CPU1_RT2_1A
  BV22  GND43  POWER  = GND
  BV32  GND44  POWER  = GND
  BW2  GND46  POWER  = GND
  BW34  GND47  POWER  = GND
  BY1  GND48  POWER  = GND
  BY35  GND49  POWER  = GND
  C2  NCF_GND3  POWER  = NCF_CPU1_P2_GND
  C34  NCF_GND4  POWER  = NCF_CPU1_P2_GND
  CA7  B_PETP7  OUT  = P5E_CPU1_P2_TX_BUF_DP<8>
  CA26  A_PETP7  OUT  = P5E_CPU1_P2_RX_DP<8>
  CB2  A_PERN7  IN  = P5E_CPU1_P2_RX_BUF_DN<8>
  CB34  B_PERP7  IN  = P5E_CPU1_P2_TX_C_DN<8>
  CC10  B_PETN7  OUT  = P5E_CPU1_P2_TX_BUF_DN<8>
  CC29  A_PETN7  OUT  = P5E_CPU1_P2_RX_DN<8>
  CD1  A_PERP7  IN  = P5E_CPU1_P2_RX_BUF_DP<8>
  CD35  B_PERN7  IN  = P5E_CPU1_P2_TX_C_DP<8>
  CE4  GND53  POWER  = GND
  CE13  GND50  POWER  = GND
  CE17  PWR_1A_2  POWER  = P1V8_CPU1_RT2_1A
  CE20  PWR_1A_3  POWER  = P1V8_CPU1_RT2_1A
  CE22  GND51  POWER  = GND
  CE32  GND52  POWER  = GND
  CF2  GND54  POWER  = GND
  CF34  GND55  POWER  = GND
  CG1  GND56  POWER  = GND
  CG35  GND57  POWER  = GND
  CH7  B_PETP8  OUT  = P5E_CPU1_P2_TX_BUF_DP<7>
  CH26  A_PETP8  OUT  = P5E_CPU1_P2_RX_DP<7>
  CJ2  A_PERN8  IN  = P5E_CPU1_P2_RX_BUF_DN<7>
  CJ34  B_PERP8  IN  = P5E_CPU1_P2_TX_C_DN<7>
  CK10  B_PETN8  OUT  = P5E_CPU1_P2_TX_BUF_DN<7>
  CK29  A_PETN8  OUT  = P5E_CPU1_P2_RX_DN<7>
  CL1  A_PERP8  IN  = P5E_CPU1_P2_RX_BUF_DP<7>
  CL35  B_PERN8  IN  = P5E_CPU1_P2_TX_C_DP<7>
  CM4  GND61  POWER  = GND
  CM13  GND58  POWER  = GND
  CM17  PWR_1A_4  POWER  = P1V8_CPU1_RT2_1A
  CM20  PWR_1A_5  POWER  = P1V8_CPU1_RT2_1A
  CM22  GND59  POWER  = GND
  CM32  GND60  POWER  = GND
  CN2  GND62  POWER  = GND
  CN34  GND63  POWER  = GND
  CP1  GND64  POWER  = GND
  CP35  GND65  POWER  = GND
  CR7  B_PETP9  OUT  = P5E_CPU1_P2_TX_BUF_DP<6>
  CR26  A_PETP9  OUT  = P5E_CPU1_P2_RX_DP<6>
  CT2  A_PERN9  IN  = P5E_CPU1_P2_RX_BUF_DN<6>
  CT34  B_PERP9  IN  = P5E_CPU1_P2_TX_C_DN<6>
  CU10  B_PETN9  OUT  = P5E_CPU1_P2_TX_BUF_DN<6>
  CU29  A_PETN9  OUT  = P5E_CPU1_P2_RX_DN<6>
  CV1  A_PERP9  IN  = P5E_CPU1_P2_RX_BUF_DP<6>
  CV35  B_PERN9  IN  = P5E_CPU1_P2_TX_C_DP<6>
  CW4  GND69  POWER  = GND
  CW13  GND66  POWER  = GND
  CW17  PWR_2D_3  POWER  = P0V9_CPU1_RT_2D
  CW20  PWR_2D_4  POWER  = P0V9_CPU1_RT_2D
  CW22  GND67  POWER  = GND
  CW32  GND68  POWER  = GND
  CY2  GND70  POWER  = GND
  CY34  GND71  POWER  = GND
  D1  NCF_GND5  POWER  = NCF_CPU1_P2_GND
  D35  NCF_GND6  POWER  = NCF_CPU1_P2_GND
  DA1  GND72  POWER  = GND
  DA35  GND73  POWER  = GND
  DB7  B_PETP10  OUT  = P5E_CPU1_P2_TX_BUF_DP<5>
  DB26  A_PETP10  OUT  = P5E_CPU1_P2_RX_DP<5>
  DC2  A_PERN10  IN  = P5E_CPU1_P2_RX_BUF_DN<5>
  DC34  B_PERP10  IN  = P5E_CPU1_P2_TX_C_DN<5>
  DD10  B_PETN10  OUT  = P5E_CPU1_P2_TX_BUF_DN<5>
  DD29  A_PETN10  OUT  = P5E_CPU1_P2_RX_DN<5>
  DE1  A_PERP10  IN  = P5E_CPU1_P2_RX_BUF_DP<5>
  DE35  B_PERN10  IN  = P5E_CPU1_P2_TX_C_DP<5>
  DF4  GND77  POWER  = GND
  DF13  GND74  POWER  = GND
  DF17  PWR_2A_9  POWER  = P0V9_CPU1_RT2_2A_2D
  DF20  PWR_2A_10  POWER  = P0V9_CPU1_RT2_2A_2D
  DF22  GND75  POWER  = GND
  DF32  GND76  POWER  = GND
  DG2  GND78  POWER  = GND
  DG34  GND79  POWER  = GND
  DH1  GND80  POWER  = GND
  DH35  GND81  POWER  = GND
  DJ7  B_PETP11  OUT  = P5E_CPU1_P2_TX_BUF_DP<4>
  DJ26  A_PETP11  OUT  = P5E_CPU1_P2_RX_DP<4>
  DK2  A_PERN11  IN  = P5E_CPU1_P2_RX_BUF_DN<4>
  DK34  B_PERP11  IN  = P5E_CPU1_P2_TX_C_DN<4>
  DL10  B_PETN11  OUT  = P5E_CPU1_P2_TX_BUF_DN<4>
  DL29  A_PETN11  OUT  = P5E_CPU1_P2_RX_DN<4>
  DM1  A_PERP11  IN  = P5E_CPU1_P2_RX_BUF_DP<4>
  DM35  B_PERN11  IN  = P5E_CPU1_P2_TX_C_DP<4>
  DN4  GND85  POWER  = GND
  DN13  GND82  POWER  = GND
  DN17  PWR_2A_11  POWER  = P0V9_CPU1_RT2_2A
  DN20  PWR_2A_12  POWER  = P0V9_CPU1_RT2_2A
  DN22  GND83  POWER  = GND
  DN32  GND84  POWER  = GND
  DP2  GND86  POWER  = GND
  DP34  GND87  POWER  = GND
  DR1  GND88  POWER  = GND
  DR35  GND89  POWER  = GND
  DT7  B_PETP12  OUT  = P5E_CPU1_P2_TX_BUF_DP<3>
  DT26  A_PETP12  OUT  = P5E_CPU1_P2_RX_DP<3>
  DU2  A_PERN12  IN  = P5E_CPU1_P2_RX_BUF_DN<3>
  DU34  B_PERP12  IN  = P5E_CPU1_P2_TX_C_DN<3>
  DV10  B_PETN12  OUT  = P5E_CPU1_P2_TX_BUF_DN<3>
  DV29  A_PETN12  OUT  = P5E_CPU1_P2_RX_DN<3>
  DW1  A_PERP12  IN  = P5E_CPU1_P2_RX_BUF_DP<3>
  DW35  B_PERN12  IN  = P5E_CPU1_P2_TX_C_DP<3>
  DY4  GND93  POWER  = GND
  DY13  GND90  POWER  = GND
  DY17  PWR_2A_13  POWER  = P0V9_CPU1_RT2_2A
  DY20  PWR_2A_14  POWER  = P0V9_CPU1_RT2_2A
  DY22  GND91  POWER  = GND
  DY32  GND92  POWER  = GND
  E8  JTAG_TRST_N  IN  = JTAG_TRST_RT_CPU1_P2_N
  E11  RXDET_BYP  IN  = RXDET_BYP_RT_CPU1_P2
  E14  GND94  POWER  = GND
  E18  REFCLK_OUTN  OUT  = NC
  E27  GND95  POWER  = GND
  E30  T_SENSE  OUT  = GND
  E33  GND96  POWER  = GND
  EA2  GND97  POWER  = GND
  EA34  GND98  POWER  = GND
  EB1  GND99  POWER  = GND
  EB35  GND100  POWER  = GND
  EC7  B_PETP13  OUT  = P5E_CPU1_P2_TX_BUF_DP<2>
  EC26  A_PETP13  OUT  = P5E_CPU1_P2_RX_DP<2>
  ED2  A_PERN13  IN  = P5E_CPU1_P2_RX_BUF_DN<2>
  ED34  B_PERP13  IN  = P5E_CPU1_P2_TX_C_DN<2>
  EE10  B_PETN13  OUT  = P5E_CPU1_P2_TX_BUF_DN<2>
  EE29  A_PETN13  OUT  = P5E_CPU1_P2_RX_DN<2>
  EF1  A_PERP13  IN  = P5E_CPU1_P2_RX_BUF_DP<2>
  EF35  B_PERN13  IN  = P5E_CPU1_P2_TX_C_DP<2>
  EG4  GND104  POWER  = GND
  EG13  GND101  POWER  = GND
  EG17  PWR_2A_15  POWER  = P0V9_CPU1_RT2_2A
  EG20  PWR_2A_16  POWER  = P0V9_CPU1_RT2_2A
  EG22  GND102  POWER  = GND
  EG32  GND103  POWER  = GND
  EH2  GND105  POWER  = GND
  EH34  GND106  POWER  = GND
  EJ1  GND107  POWER  = GND
  EJ35  GND108  POWER  = GND
  EK7  B_PETP14  OUT  = P5E_CPU1_P2_TX_BUF_DP<1>
  EK26  A_PETP14  OUT  = P5E_CPU1_P2_RX_DP<1>
  EL2  A_PERN14  IN  = P5E_CPU1_P2_RX_BUF_DN<1>
  EL34  B_PERP14  IN  = P5E_CPU1_P2_TX_C_DP<1>
  EM10  B_PETN14  OUT  = P5E_CPU1_P2_TX_BUF_DN<1>
  EM29  A_PETN14  OUT  = P5E_CPU1_P2_RX_DN<1>
  EN1  A_PERP14  IN  = P5E_CPU1_P2_RX_BUF_DP<1>
  EN35  B_PERN14  IN  = P5E_CPU1_P2_TX_C_DN<1>
  EP4  GND112  POWER  = GND
  EP13  GND109  POWER  = GND
  EP17  PWR_2A_17  POWER  = P0V9_CPU1_RT2_2A
  EP20  PWR_2A_18  POWER  = P0V9_CPU1_RT2_2A
  EP22  GND110  POWER  = GND
  EP32  GND111  POWER  = GND
  ER2  GND113  POWER  = GND
  ER34  GND114  POWER  = GND
  ET1  GND115  POWER  = GND
  ET35  GND116  POWER  = GND
  EU7  B_PETP15  OUT  = P5E_CPU1_P2_TX_BUF_DP<0>
  EU26  A_PETP15  OUT  = P5E_CPU1_P2_RX_DP<0>
  EV2  A_PERN15  IN  = P5E_CPU1_P2_RX_BUF_DN<0>
  EV34  B_PERP15  IN  = P5E_CPU1_P2_TX_C_DN<0>
  EW10  B_PETN15  OUT  = P5E_CPU1_P2_TX_BUF_DN<0>
  EW29  A_PETN15  OUT  = P5E_CPU1_P2_RX_DN<0>
  EY1  A_PERP15  IN  = P5E_CPU1_P2_RX_BUF_DP<0>
  EY35  B_PERN15  IN  = P5E_CPU1_P2_TX_C_DP<0>
  F2  PERST_N  IN  = RST_RT_CPU1_P2_PERST_N
  F34  SMB_ADDR1  IN  = RT_CPU1_P2_ADDR1
  FA15  GND117  POWER  = GND
  FA32  GND118  POWER  = GND
  FB2  GND119  POWER  = GND
  FB34  GND120  POWER  = GND
  FC3  GND125  POWER  = GND
  FC6  GND126  POWER  = GND
  FC9  GND127  POWER  = GND
  FC19  GND121  POWER  = GND
  FC23  GND122  POWER  = GND
  FC25  GND123  POWER  = GND
  FC28  GND124  POWER  = GND
  FD1  GND128  POWER  = GND
  FD35  GND129  POWER  = GND
  FE2  NCF_GND7  POWER  = NCF_CPU1_P2_GND
  FE34  NCF_GND8  POWER  = NCF_CPU1_P2_GND
  FF5  EE_CLK  BI  = SMB_RT_CPU1_P2_ROM_MUX_1D_R_SCL
  FF8  JTAG_TEST_MODE  IN  = JTAG_TEST_MODE_RT_CPU1_P2
  FF11  RESET_N  IN  = RST_RT_CPU1_P2_RESET_N
  FF14  GND130  POWER  = GND
  FF18  REFCLKN  IN  = CLK_100M_RETIMER_CPU1_P2_DN
  FF21  GND131  POWER  = GND
  FF24  TEST0  BI  = TEST0_RT_CPU1_P2
  FF27  TEST1  BI  = TEST1_RT_CPU1_P2
  FF30  TEST2  BI  = TEST2_RT_CPU1_P2
  FF33  SCAN_MODE  IN  = RT_CPU1_P2_SCAN_MODE
  FG1  NCF_GND9  POWER  = NCF_CPU1_P2_GND
  FG35  NCF_GND10  POWER  = NCF_CPU1_P2_GND
  FH2  NCF_GND11  POWER  = NCF_CPU1_P2_GND
  FH34  NCF_GND12  POWER  = NCF_CPU1_P2_GND
  FJ3  EE_DAT  BI  = SMB_RT_CPU1_P2_ROM_MUX_1D_R_SDA
  FJ6  GPIO0  BI  = NC
  FJ9  MODE  IN  = MODE_RT_CPU1_P2
  FJ12  GND132  POWER  = GND
  FJ16  REFCLKP  IN  = CLK_100M_RETIMER_CPU1_P2_DP
  FJ19  GND133  POWER  = GND
  FJ23  GPIO1  BI  = NC
  FJ25  GPIO2  BI  = GPIO2_RT_CPU1_P2
  FJ28  GPIO3  BI  = GPIO3_RT_CPU1_P2
  FJ31  INT_N  OUT  = NC
  G1  VQPS  IN  = RT_CPU1_P2_VQPS
  G35  CLKREQ_N  IN  = CLKREQ_RT_CPU1_P2_N
  H12  GND134  POWER  = GND
  H16  GND135  POWER  = GND
  H19  GND136  POWER  = GND
  H31  GND137  POWER  = GND
  J4  GND139  POWER  = GND
  J22  GND138  POWER  = GND
  K2  GND140  POWER  = GND
  K34  GND141  POWER  = GND
  L1  GND142  POWER  = GND
  L35  GND143  POWER  = GND
  M7  B_PETP0  OUT  = P5E_CPU1_P2_TX_BUF_DP<15>
  M26  A_PETP0  OUT  = P5E_CPU1_P2_RX_DP<15>
  N2  A_PERN0  IN  = P5E_CPU1_P2_RX_BUF_DN<15>
  N34  B_PERP0  IN  = P5E_CPU1_P2_TX_C_DN<15>
  P10  B_PETN0  OUT  = P5E_CPU1_P2_TX_BUF_DN<15>
  P29  A_PETN0  OUT  = P5E_CPU1_P2_RX_DN<15>
  R1  A_PERP0  IN  = P5E_CPU1_P2_RX_BUF_DP<15>
  R35  B_PERN0  IN  = P5E_CPU1_P2_TX_C_DP<15>
  T4  GND147  POWER  = GND
  T13  GND144  POWER  = GND
  T17  PWR_2A_19  POWER  = P0V9_CPU1_RT2_2A
  T20  PWR_2A_20  POWER  = P0V9_CPU1_RT2_2A
  T22  GND145  POWER  = GND
  T32  GND146  POWER  = GND
  U2  GND148  POWER  = GND
  U34  GND149  POWER  = GND
  V1  GND150  POWER  = GND
  V35  GND151  POWER  = GND
  W7  B_PETP1  OUT  = P5E_CPU1_P2_TX_BUF_DP<14>
  W26  A_PETP1  OUT  = P5E_CPU1_P2_RX_DP<14>
  Y2  A_PERN1  IN  = P5E_CPU1_P2_RX_BUF_DN<14>
  Y34  B_PERP1  IN  = P5E_CPU1_P2_TX_C_DN<14>
